(kicad_pcb
	(version 20260206)
	(generator "pcbnew")
	(generator_version "10.0")
	(general
		(thickness 1.6)
		(legacy_teardrops no)
	)
	(paper "A4")
	(title_block
		(title "03242023_DA0F0TMBIJ0_F0T_Motherboard_J_brd_V01_OCP.brd")
		(comment 1 "Grand Teton / footprint 1607 of 6105 (J10), pads 113-224 of 291")
	)
	(layers
		(0 "F.Cu" signal "TOP")
		(4 "In1.Cu" signal "GND")
		(6 "In2.Cu" signal "IN1")
		(8 "In3.Cu" signal "GND1")
		(10 "In4.Cu" signal "IN2")
		(12 "In5.Cu" signal "GND2")
		(14 "In6.Cu" signal "IN3")
		(16 "In7.Cu" signal "GND3")
		(18 "In8.Cu" signal "VCC")
		(20 "In9.Cu" signal "VCC1")
		(22 "In10.Cu" signal "GND4")
		(24 "In11.Cu" signal "IN4")
		(26 "In12.Cu" signal "GND5")
		(28 "In13.Cu" signal "IN5")
		(30 "In14.Cu" signal "GND6")
		(32 "In15.Cu" signal "IN6")
		(34 "In16.Cu" signal "GND7")
		(2 "B.Cu" signal "BOTTOM")
		(9 "F.Adhes" user "F.Adhesive")
		(11 "B.Adhes" user "B.Adhesive")
		(13 "F.Paste" user "Package Geometry/Pastemask Top")
		(15 "B.Paste" user "Package Geometry/Pastemask Bottom")
		(5 "F.SilkS" user "Ref Des/Silkscreen Top")
		(7 "B.SilkS" user "Ref Des/Silkscreen Bottom")
		(1 "F.Mask" user "Board Geometry/Soldermask Top")
		(3 "B.Mask" user "Board Geometry/Soldermask Bottom")
		(17 "Dwgs.User" user "User.Drawings")
		(19 "Cmts.User" user "User.Comments")
		(21 "Eco1.User" user "User.Eco1")
		(23 "Eco2.User" user "User.Eco2")
		(25 "Edge.Cuts" user "Board Geometry/Outline")
		(27 "Margin" user)
		(31 "F.CrtYd" user "Package Geometry/Place Bound Top")
		(29 "B.CrtYd" user "Package Geometry/Place Bound Bottom")
		(35 "F.Fab" user "Ref Des/Assembly Top")
		(33 "B.Fab" user "Ref Des/Assembly Bottom")
	)
	(footprint ""
		(layer "F.Cu")
		(at 408.803348 -258.091686)
		(property "Reference" "J10"
			(at -3.683 -81.702148 0)
			(unlocked yes)
			(layer "F.SilkS")
			(effects
				(font
					(size 0.7874 0.5842)
					(thickness 0.1524)
				)
				(justify left)
			)
		)
		(property "Value" ""
			(at 0 0 0)
			(layer "F.Fab")
			(effects
				(font
					(size 1.27 1.27)
				)
			)
		)
		(duplicate_pad_numbers_are_jumpers no)
		(pad "113" smd rect
			(at -2.050034 36.975034 270)
			(size 0.519938 1.4986)
			(layers "F.Cu" "F.Mask" "F.Paste")
			(net "M_E_CPU0_SB_DQ<9>")
		)
		(pad "114" smd rect
			(at -2.050034 37.824918 270)
			(size 0.519938 1.4986)
			(layers "F.Cu" "F.Mask" "F.Paste")
			(net "GND")
		)
		(pad "115" smd rect
			(at -2.050034 38.675056 270)
			(size 0.519938 1.4986)
			(layers "F.Cu" "F.Mask" "F.Paste")
			(net "M_E_CPU0_SB_DQS_DP<1>")
		)
		(pad "116" smd rect
			(at -2.050034 39.52494 270)
			(size 0.519938 1.4986)
			(layers "F.Cu" "F.Mask" "F.Paste")
			(net "M_E_CPU0_SB_DQS_DN<1>")
		)
		(pad "117" smd rect
			(at -2.050034 40.375078 270)
			(size 0.519938 1.4986)
			(layers "F.Cu" "F.Mask" "F.Paste")
			(net "GND")
		)
		(pad "118" smd rect
			(at -2.050034 41.224962 270)
			(size 0.519938 1.4986)
			(layers "F.Cu" "F.Mask" "F.Paste")
			(net "M_E_CPU0_SB_DQ<12>")
		)
		(pad "119" smd rect
			(at -2.050034 42.0751 270)
			(size 0.519938 1.4986)
			(layers "F.Cu" "F.Mask" "F.Paste")
			(net "GND")
		)
		(pad "120" smd rect
			(at -2.050034 42.924984 270)
			(size 0.519938 1.4986)
			(layers "F.Cu" "F.Mask" "F.Paste")
			(net "M_E_CPU0_SB_DQ<13>")
		)
		(pad "121" smd rect
			(at -2.050034 43.775122 270)
			(size 0.519938 1.4986)
			(layers "F.Cu" "F.Mask" "F.Paste")
			(net "GND")
		)
		(pad "122" smd rect
			(at -2.050034 44.625006 270)
			(size 0.519938 1.4986)
			(layers "F.Cu" "F.Mask" "F.Paste")
			(net "M_E_CPU0_SB_DQ<16>")
		)
		(pad "123" smd rect
			(at -2.050034 45.47489 270)
			(size 0.519938 1.4986)
			(layers "F.Cu" "F.Mask" "F.Paste")
			(net "GND")
		)
		(pad "124" smd rect
			(at -2.050034 46.325028 270)
			(size 0.519938 1.4986)
			(layers "F.Cu" "F.Mask" "F.Paste")
			(net "M_E_CPU0_SB_DQ<17>")
		)
		(pad "125" smd rect
			(at -2.050034 47.174912 270)
			(size 0.519938 1.4986)
			(layers "F.Cu" "F.Mask" "F.Paste")
			(net "GND")
		)
		(pad "126" smd rect
			(at -2.050034 48.02505 270)
			(size 0.519938 1.4986)
			(layers "F.Cu" "F.Mask" "F.Paste")
			(net "M_E_CPU0_SB_DQS_DP<2>")
		)
		(pad "127" smd rect
			(at -2.050034 48.874934 270)
			(size 0.519938 1.4986)
			(layers "F.Cu" "F.Mask" "F.Paste")
			(net "M_E_CPU0_SB_DQS_DN<2>")
		)
		(pad "128" smd rect
			(at -2.050034 49.725072 270)
			(size 0.519938 1.4986)
			(layers "F.Cu" "F.Mask" "F.Paste")
			(net "GND")
		)
		(pad "129" smd rect
			(at -2.050034 50.574956 270)
			(size 0.519938 1.4986)
			(layers "F.Cu" "F.Mask" "F.Paste")
			(net "M_E_CPU0_SB_DQ<20>")
		)
		(pad "130" smd rect
			(at -2.050034 51.425094 270)
			(size 0.519938 1.4986)
			(layers "F.Cu" "F.Mask" "F.Paste")
			(net "GND")
		)
		(pad "131" smd rect
			(at -2.050034 52.274978 270)
			(size 0.519938 1.4986)
			(layers "F.Cu" "F.Mask" "F.Paste")
			(net "M_E_CPU0_SB_DQ<21>")
		)
		(pad "132" smd rect
			(at -2.050034 53.125116 270)
			(size 0.519938 1.4986)
			(layers "F.Cu" "F.Mask" "F.Paste")
			(net "GND")
		)
		(pad "133" smd rect
			(at -2.050034 53.975 270)
			(size 0.519938 1.4986)
			(layers "F.Cu" "F.Mask" "F.Paste")
			(net "M_E_CPU0_SB_DQ<24>")
		)
		(pad "134" smd rect
			(at -2.050034 54.824884 270)
			(size 0.519938 1.4986)
			(layers "F.Cu" "F.Mask" "F.Paste")
			(net "GND")
		)
		(pad "135" smd rect
			(at -2.050034 55.675022 270)
			(size 0.519938 1.4986)
			(layers "F.Cu" "F.Mask" "F.Paste")
			(net "M_E_CPU0_SB_DQ<25>")
		)
		(pad "136" smd rect
			(at -2.050034 56.524906 270)
			(size 0.519938 1.4986)
			(layers "F.Cu" "F.Mask" "F.Paste")
			(net "GND")
		)
		(pad "137" smd rect
			(at -2.050034 57.375044 270)
			(size 0.519938 1.4986)
			(layers "F.Cu" "F.Mask" "F.Paste")
			(net "M_E_CPU0_SB_DQS_DP<3>")
		)
		(pad "138" smd rect
			(at -2.050034 58.224928 270)
			(size 0.519938 1.4986)
			(layers "F.Cu" "F.Mask" "F.Paste")
			(net "M_E_CPU0_SB_DQS_DN<3>")
		)
		(pad "139" smd rect
			(at -2.050034 59.075066 270)
			(size 0.519938 1.4986)
			(layers "F.Cu" "F.Mask" "F.Paste")
			(net "GND")
		)
		(pad "140" smd rect
			(at -2.050034 59.92495 270)
			(size 0.519938 1.4986)
			(layers "F.Cu" "F.Mask" "F.Paste")
			(net "M_E_CPU0_SB_DQ<28>")
		)
		(pad "141" smd rect
			(at -2.050034 60.775088 270)
			(size 0.519938 1.4986)
			(layers "F.Cu" "F.Mask" "F.Paste")
			(net "GND")
		)
		(pad "142" smd rect
			(at -2.050034 61.624972 270)
			(size 0.519938 1.4986)
			(layers "F.Cu" "F.Mask" "F.Paste")
			(net "M_E_CPU0_SB_DQ<29>")
		)
		(pad "143" smd rect
			(at -2.050034 62.47511 270)
			(size 0.519938 1.4986)
			(layers "F.Cu" "F.Mask" "F.Paste")
			(net "GND")
		)
		(pad "144" smd rect
			(at -2.050034 63.324994 270)
			(size 0.519938 1.4986)
			(layers "F.Cu" "F.Mask" "F.Paste")
			(net "TP_CHE_CPU0_DIMM2_FRU_1")
		)
		(pad "145" smd rect
			(at 2.050034 -63.324994 270)
			(size 0.519938 1.4986)
			(layers "F.Cu" "F.Mask" "F.Paste")
			(net "P12V_S3_AUX_CPU0_NVDIMM")
		)
		(pad "146" smd rect
			(at 2.050034 -62.47511 270)
			(size 0.519938 1.4986)
			(layers "F.Cu" "F.Mask" "F.Paste")
			(net "P12V_S3_AUX_CPU0_NVDIMM")
		)
		(pad "147" smd rect
			(at 2.050034 -61.624972 270)
			(size 0.519938 1.4986)
			(layers "F.Cu" "F.Mask" "F.Paste")
			(net "PWRGD_CHE_CPU0_DIMM2")
		)
		(pad "148" smd rect
			(at 2.050034 -60.775088 270)
			(size 0.519938 1.4986)
			(layers "F.Cu" "F.Mask" "F.Paste")
			(net "PD_CHE_CPU0_DIMM2_SAA")
		)
		(pad "149" smd rect
			(at 2.050034 -59.92495 270)
			(size 0.519938 1.4986)
			(layers "F.Cu" "F.Mask" "F.Paste")
			(net "TP_CHE_CPU0_DIMM2_FRU_2")
		)
		(pad "150" smd rect
			(at 2.050034 -59.075066 270)
			(size 0.519938 1.4986)
			(layers "F.Cu" "F.Mask" "F.Paste")
			(net "TP_CHE_CPU0_DIMM2_FRU_3")
		)
		(pad "151" smd rect
			(at 2.050034 -58.224928 270)
			(size 0.519938 1.4986)
			(layers "F.Cu" "F.Mask" "F.Paste")
			(net "GND")
		)
		(pad "152" smd rect
			(at 2.050034 -57.375044 270)
			(size 0.519938 1.4986)
			(layers "F.Cu" "F.Mask" "F.Paste")
			(net "M_E_CPU0_SA_DQ<2>")
		)
		(pad "153" smd rect
			(at 2.050034 -56.524906 270)
			(size 0.519938 1.4986)
			(layers "F.Cu" "F.Mask" "F.Paste")
			(net "GND")
		)
		(pad "154" smd rect
			(at 2.050034 -55.675022 270)
			(size 0.519938 1.4986)
			(layers "F.Cu" "F.Mask" "F.Paste")
			(net "M_E_CPU0_SA_DQ<3>")
		)
		(pad "155" smd rect
			(at 2.050034 -54.824884 270)
			(size 0.519938 1.4986)
			(layers "F.Cu" "F.Mask" "F.Paste")
			(net "GND")
		)
		(pad "156" smd rect
			(at 2.050034 -53.975 270)
			(size 0.519938 1.4986)
			(layers "F.Cu" "F.Mask" "F.Paste")
			(net "M_E_CPU0_SA_DQS_DN<5>")
		)
		(pad "157" smd rect
			(at 2.050034 -53.125116 270)
			(size 0.519938 1.4986)
			(layers "F.Cu" "F.Mask" "F.Paste")
			(net "M_E_CPU0_SA_DQS_DP<5>")
		)
		(pad "158" smd rect
			(at 2.050034 -52.274978 270)
			(size 0.519938 1.4986)
			(layers "F.Cu" "F.Mask" "F.Paste")
			(net "GND")
		)
		(pad "159" smd rect
			(at 2.050034 -51.425094 270)
			(size 0.519938 1.4986)
			(layers "F.Cu" "F.Mask" "F.Paste")
			(net "M_E_CPU0_SA_DQ<6>")
		)
		(pad "160" smd rect
			(at 2.050034 -50.574956 270)
			(size 0.519938 1.4986)
			(layers "F.Cu" "F.Mask" "F.Paste")
			(net "GND")
		)
		(pad "161" smd rect
			(at 2.050034 -49.725072 270)
			(size 0.519938 1.4986)
			(layers "F.Cu" "F.Mask" "F.Paste")
			(net "M_E_CPU0_SA_DQ<7>")
		)
		(pad "162" smd rect
			(at 2.050034 -48.874934 270)
			(size 0.519938 1.4986)
			(layers "F.Cu" "F.Mask" "F.Paste")
			(net "GND")
		)
		(pad "163" smd rect
			(at 2.050034 -48.02505 270)
			(size 0.519938 1.4986)
			(layers "F.Cu" "F.Mask" "F.Paste")
			(net "M_E_CPU0_SA_DQ<10>")
		)
		(pad "164" smd rect
			(at 2.050034 -47.174912 270)
			(size 0.519938 1.4986)
			(layers "F.Cu" "F.Mask" "F.Paste")
			(net "GND")
		)
		(pad "165" smd rect
			(at 2.050034 -46.325028 270)
			(size 0.519938 1.4986)
			(layers "F.Cu" "F.Mask" "F.Paste")
			(net "M_E_CPU0_SA_DQ<11>")
		)
		(pad "166" smd rect
			(at 2.050034 -45.47489 270)
			(size 0.519938 1.4986)
			(layers "F.Cu" "F.Mask" "F.Paste")
			(net "GND")
		)
		(pad "167" smd rect
			(at 2.050034 -44.625006 270)
			(size 0.519938 1.4986)
			(layers "F.Cu" "F.Mask" "F.Paste")
			(net "M_E_CPU0_SA_DQS_DN<6>")
		)
		(pad "168" smd rect
			(at 2.050034 -43.775122 270)
			(size 0.519938 1.4986)
			(layers "F.Cu" "F.Mask" "F.Paste")
			(net "M_E_CPU0_SA_DQS_DP<6>")
		)
		(pad "169" smd rect
			(at 2.050034 -42.924984 270)
			(size 0.519938 1.4986)
			(layers "F.Cu" "F.Mask" "F.Paste")
			(net "GND")
		)
		(pad "170" smd rect
			(at 2.050034 -42.0751 270)
			(size 0.519938 1.4986)
			(layers "F.Cu" "F.Mask" "F.Paste")
			(net "M_E_CPU0_SA_DQ<14>")
		)
		(pad "171" smd rect
			(at 2.050034 -41.224962 270)
			(size 0.519938 1.4986)
			(layers "F.Cu" "F.Mask" "F.Paste")
			(net "GND")
		)
		(pad "172" smd rect
			(at 2.050034 -40.375078 270)
			(size 0.519938 1.4986)
			(layers "F.Cu" "F.Mask" "F.Paste")
			(net "M_E_CPU0_SA_DQ<15>")
		)
		(pad "173" smd rect
			(at 2.050034 -39.52494 270)
			(size 0.519938 1.4986)
			(layers "F.Cu" "F.Mask" "F.Paste")
			(net "GND")
		)
		(pad "174" smd rect
			(at 2.050034 -38.675056 270)
			(size 0.519938 1.4986)
			(layers "F.Cu" "F.Mask" "F.Paste")
			(net "M_E_CPU0_SA_DQ<18>")
		)
		(pad "175" smd rect
			(at 2.050034 -37.824918 270)
			(size 0.519938 1.4986)
			(layers "F.Cu" "F.Mask" "F.Paste")
			(net "GND")
		)
		(pad "176" smd rect
			(at 2.050034 -36.975034 270)
			(size 0.519938 1.4986)
			(layers "F.Cu" "F.Mask" "F.Paste")
			(net "M_E_CPU0_SA_DQ<19>")
		)
		(pad "177" smd rect
			(at 2.050034 -36.124896 270)
			(size 0.519938 1.4986)
			(layers "F.Cu" "F.Mask" "F.Paste")
			(net "GND")
		)
		(pad "178" smd rect
			(at 2.050034 -35.275012 270)
			(size 0.519938 1.4986)
			(layers "F.Cu" "F.Mask" "F.Paste")
			(net "M_E_CPU0_SA_DQS_DN<7>")
		)
		(pad "179" smd rect
			(at 2.050034 -34.425128 270)
			(size 0.519938 1.4986)
			(layers "F.Cu" "F.Mask" "F.Paste")
			(net "M_E_CPU0_SA_DQS_DP<7>")
		)
		(pad "180" smd rect
			(at 2.050034 -33.57499 270)
			(size 0.519938 1.4986)
			(layers "F.Cu" "F.Mask" "F.Paste")
			(net "GND")
		)
		(pad "181" smd rect
			(at 2.050034 -32.725106 270)
			(size 0.519938 1.4986)
			(layers "F.Cu" "F.Mask" "F.Paste")
			(net "M_E_CPU0_SA_DQ<22>")
		)
		(pad "182" smd rect
			(at 2.050034 -31.874968 270)
			(size 0.519938 1.4986)
			(layers "F.Cu" "F.Mask" "F.Paste")
			(net "GND")
		)
		(pad "183" smd rect
			(at 2.050034 -31.025084 270)
			(size 0.519938 1.4986)
			(layers "F.Cu" "F.Mask" "F.Paste")
			(net "M_E_CPU0_SA_DQ<23>")
		)
		(pad "184" smd rect
			(at 2.050034 -30.174946 270)
			(size 0.519938 1.4986)
			(layers "F.Cu" "F.Mask" "F.Paste")
			(net "GND")
		)
		(pad "185" smd rect
			(at 2.050034 -29.325062 270)
			(size 0.519938 1.4986)
			(layers "F.Cu" "F.Mask" "F.Paste")
			(net "M_E_CPU0_SA_DQ<26>")
		)
		(pad "186" smd rect
			(at 2.050034 -28.474924 270)
			(size 0.519938 1.4986)
			(layers "F.Cu" "F.Mask" "F.Paste")
			(net "GND")
		)
		(pad "187" smd rect
			(at 2.050034 -27.62504 270)
			(size 0.519938 1.4986)
			(layers "F.Cu" "F.Mask" "F.Paste")
			(net "M_E_CPU0_SA_DQ<27>")
		)
		(pad "188" smd rect
			(at 2.050034 -26.774902 270)
			(size 0.519938 1.4986)
			(layers "F.Cu" "F.Mask" "F.Paste")
			(net "GND")
		)
		(pad "189" smd rect
			(at 2.050034 -25.925018 270)
			(size 0.519938 1.4986)
			(layers "F.Cu" "F.Mask" "F.Paste")
			(net "M_E_CPU0_SA_DQS_DN<8>")
		)
		(pad "190" smd rect
			(at 2.050034 -25.07488 270)
			(size 0.519938 1.4986)
			(layers "F.Cu" "F.Mask" "F.Paste")
			(net "M_E_CPU0_SA_DQS_DP<8>")
		)
		(pad "191" smd rect
			(at 2.050034 -24.224996 270)
			(size 0.519938 1.4986)
			(layers "F.Cu" "F.Mask" "F.Paste")
			(net "GND")
		)
		(pad "192" smd rect
			(at 2.050034 -23.375112 270)
			(size 0.519938 1.4986)
			(layers "F.Cu" "F.Mask" "F.Paste")
			(net "M_E_CPU0_SA_DQ<30>")
		)
		(pad "193" smd rect
			(at 2.050034 -22.524974 270)
			(size 0.519938 1.4986)
			(layers "F.Cu" "F.Mask" "F.Paste")
			(net "GND")
		)
		(pad "194" smd rect
			(at 2.050034 -21.67509 270)
			(size 0.519938 1.4986)
			(layers "F.Cu" "F.Mask" "F.Paste")
			(net "M_E_CPU0_SA_DQ<31>")
		)
		(pad "195" smd rect
			(at 2.050034 -20.824952 270)
			(size 0.519938 1.4986)
			(layers "F.Cu" "F.Mask" "F.Paste")
			(net "GND")
		)
		(pad "196" smd rect
			(at 2.050034 -19.975068 270)
			(size 0.519938 1.4986)
			(layers "F.Cu" "F.Mask" "F.Paste")
			(net "M_E_CPU0_SA_CB<2>")
		)
		(pad "197" smd rect
			(at 2.050034 -19.12493 270)
			(size 0.519938 1.4986)
			(layers "F.Cu" "F.Mask" "F.Paste")
			(net "GND")
		)
		(pad "198" smd rect
			(at 2.050034 -18.275046 270)
			(size 0.519938 1.4986)
			(layers "F.Cu" "F.Mask" "F.Paste")
			(net "M_E_CPU0_SA_CB<3>")
		)
		(pad "199" smd rect
			(at 2.050034 -17.424908 270)
			(size 0.519938 1.4986)
			(layers "F.Cu" "F.Mask" "F.Paste")
			(net "GND")
		)
		(pad "200" smd rect
			(at 2.050034 -16.575024 270)
			(size 0.519938 1.4986)
			(layers "F.Cu" "F.Mask" "F.Paste")
			(net "M_E_CPU0_SA_DQS_DN<9>")
		)
		(pad "201" smd rect
			(at 2.050034 -15.724886 270)
			(size 0.519938 1.4986)
			(layers "F.Cu" "F.Mask" "F.Paste")
			(net "M_E_CPU0_SA_DQS_DP<9>")
		)
		(pad "202" smd rect
			(at 2.050034 -14.875002 270)
			(size 0.519938 1.4986)
			(layers "F.Cu" "F.Mask" "F.Paste")
			(net "GND")
		)
		(pad "203" smd rect
			(at 2.050034 -14.025118 270)
			(size 0.519938 1.4986)
			(layers "F.Cu" "F.Mask" "F.Paste")
			(net "M_E_CPU0_SA_CB<6>")
		)
		(pad "204" smd rect
			(at 2.050034 -13.17498 270)
			(size 0.519938 1.4986)
			(layers "F.Cu" "F.Mask" "F.Paste")
			(net "GND")
		)
		(pad "205" smd rect
			(at 2.050034 -12.325096 270)
			(size 0.519938 1.4986)
			(layers "F.Cu" "F.Mask" "F.Paste")
			(net "M_E_CPU0_SA_CB<7>")
		)
		(pad "206" smd rect
			(at 2.050034 -11.474958 270)
			(size 0.519938 1.4986)
			(layers "F.Cu" "F.Mask" "F.Paste")
			(net "GND")
		)
		(pad "207" smd rect
			(at 2.050034 -10.625074 270)
			(size 0.519938 1.4986)
			(layers "F.Cu" "F.Mask" "F.Paste")
			(net "RST_M_EF_CPU0_FPGA_N")
		)
		(pad "208" smd rect
			(at 2.050034 -9.774936 270)
			(size 0.519938 1.4986)
			(layers "F.Cu" "F.Mask" "F.Paste")
			(net "GND")
		)
		(pad "209" smd rect
			(at 2.050034 -8.925052 270)
			(size 0.519938 1.4986)
			(layers "F.Cu" "F.Mask" "F.Paste")
			(net "M_E_CPU0_SA_CS_N<3>")
		)
		(pad "210" smd rect
			(at 2.050034 -8.074914 270)
			(size 0.519938 1.4986)
			(layers "F.Cu" "F.Mask" "F.Paste")
			(net "GND")
		)
		(pad "211" smd rect
			(at 2.050034 -7.22503 270)
			(size 0.519938 1.4986)
			(layers "F.Cu" "F.Mask" "F.Paste")
			(net "M_E_CPU0_SA_CA<1>")
		)
		(pad "212" smd rect
			(at 2.050034 -6.374892 270)
			(size 0.519938 1.4986)
			(layers "F.Cu" "F.Mask" "F.Paste")
			(net "GND")
		)
		(pad "213" smd rect
			(at 2.050034 -5.525008 270)
			(size 0.519938 1.4986)
			(layers "F.Cu" "F.Mask" "F.Paste")
			(net "M_E_CPU0_SA_CA<3>")
		)
		(pad "214" smd rect
			(at 2.050034 -4.675124 270)
			(size 0.519938 1.4986)
			(layers "F.Cu" "F.Mask" "F.Paste")
			(net "GND")
		)
		(pad "215" smd rect
			(at 2.050034 -3.824986 270)
			(size 0.519938 1.4986)
			(layers "F.Cu" "F.Mask" "F.Paste")
			(net "M_E_CPU0_SA_CA<5>")
		)
		(pad "216" smd rect
			(at 2.050034 -2.975102 270)
			(size 0.519938 1.4986)
			(layers "F.Cu" "F.Mask" "F.Paste")
			(net "GND")
		)
		(pad "217" smd rect
			(at 2.050034 -2.124964 270)
			(size 0.519938 1.4986)
			(layers "F.Cu" "F.Mask" "F.Paste")
			(net "M_E_CPU0_CLK_DP<1>")
		)
		(pad "218" smd rect
			(at 2.050034 -1.27508 270)
			(size 0.519938 1.4986)
			(layers "F.Cu" "F.Mask" "F.Paste")
			(net "M_E_CPU0_CLK_DN<1>")
		)
		(pad "219" smd rect
			(at 2.050034 -0.424942 270)
			(size 0.519938 1.4986)
			(layers "F.Cu" "F.Mask" "F.Paste")
			(net "GND")
		)
		(pad "220" smd rect
			(at 2.050034 5.525008 270)
			(size 0.519938 1.4986)
			(layers "F.Cu" "F.Mask" "F.Paste")
			(net "TP_CHE_CPU0_DIMM2_FRU_4")
		)
		(pad "221" smd rect
			(at 2.050034 6.374892 270)
			(size 0.519938 1.4986)
			(layers "F.Cu" "F.Mask" "F.Paste")
			(net "M_E_CPU0_SB_CA<1>")
		)
		(pad "222" smd rect
			(at 2.050034 7.22503 270)
			(size 0.519938 1.4986)
			(layers "F.Cu" "F.Mask" "F.Paste")
			(net "GND")
		)
		(pad "223" smd rect
			(at 2.050034 8.074914 270)
			(size 0.519938 1.4986)
			(layers "F.Cu" "F.Mask" "F.Paste")
			(net "M_E_CPU0_SB_CA<3>")
		)
		(pad "224" smd rect
			(at 2.050034 8.925052 270)
			(size 0.519938 1.4986)
			(layers "F.Cu" "F.Mask" "F.Paste")
			(net "GND")
		)
	)
)
